# BASEBOARD_FAB2 (Tioga Pass) — schematic netlist excerpt (pin names and nets, part order shuffled) for the footprints in the layout excerpt that follows; sources: Cadence DE-HDL packaged netlist, KiCad conversion of Wiwynn_Tioga_Pass_MB.brd

C25W56  CAP  1.0UF 16V 10% X6S  pkg 0402  page 149 : A = VCC_PA_3V3 ; B = GND
C8M8  CAP_A  47UF 4V 20% X5R  pkg 0603V  page 228 : A = PVDDQ_KLM ; B = GND
R4P21  RES  240 1.0% CHIP  pkg 0402  page 97 : A = PVCCIO_CPU0 ; B = PU_CPU0_TSC_SYNC

(kicad_pcb
	(version 20260206)
	(generator "pcbnew")
	(generator_version "10.0")
	(general
		(thickness 1.6)
		(legacy_teardrops no)
	)
	(paper "A4")
	(title_block
		(title "Wiwynn_Tioga_Pass_MB.brd")
		(comment 1 "Tioga Pass / footprints 2706-2708 of 4770")
	)
	(layers
		(0 "F.Cu" signal "TOP")
		(4 "In1.Cu" signal "L2GND")
		(6 "In2.Cu" signal "L3")
		(8 "In3.Cu" signal "L4GND")
		(10 "In4.Cu" signal "L5")
		(12 "In5.Cu" signal "L6GND")
		(14 "In6.Cu" signal "L7VCC")
		(16 "In7.Cu" signal "L8VCC")
		(18 "In8.Cu" signal "L9GND")
		(20 "In9.Cu" signal "L10")
		(22 "In10.Cu" signal "L11GND")
		(24 "In11.Cu" signal "L12")
		(26 "In12.Cu" signal "L13GND")
		(2 "B.Cu" signal "BOTTOM")
		(9 "F.Adhes" user "F.Adhesive")
		(11 "B.Adhes" user "B.Adhesive")
		(13 "F.Paste" user "Package Geometry/Pastemask Top")
		(15 "B.Paste" user "Package Geometry/Pastemask Bottom")
		(5 "F.SilkS" user "Ref Des/Silkscreen Top")
		(7 "B.SilkS" user "Ref Des/Silkscreen Bottom")
		(1 "F.Mask" user "Board Geometry/Soldermask Top")
		(3 "B.Mask" user "Board Geometry/Soldermask Bottom")
		(17 "Dwgs.User" user "User.Drawings")
		(19 "Cmts.User" user "User.Comments")
		(21 "Eco1.User" user "User.Eco1")
		(23 "Eco2.User" user "User.Eco2")
		(25 "Edge.Cuts" user "Board Geometry/Outline")
		(27 "Margin" user)
		(31 "F.CrtYd" user "Package Geometry/Place Bound Top")
		(29 "B.CrtYd" user "Package Geometry/Place Bound Bottom")
		(35 "F.Fab" user "Ref Des/Assembly Top")
		(33 "B.Fab" user "Ref Des/Assembly Bottom")
	)
	(footprint ""
		(layer "B.Cu")
		(at 424.200574 -40.982646 180)
		(property "Reference" "C25W56"
			(at 0.8382 -0.67818 180)
			(unlocked yes)
			(layer "B.SilkS")
			(effects
				(font
					(size 0.4064 0.254)
					(thickness 0.1524)
				)
				(justify left mirror)
			)
		)
		(property "Value" ""
			(at 0 0 0)
			(layer "B.Fab")
			(effects
				(font
					(size 1.27 1.27)
				)
				(justify mirror)
			)
		)
		(duplicate_pad_numbers_are_jumpers no)
		(fp_poly
			(pts
				(xy -0.3048 -0.1016) (xy -0.3048 0.9906) (xy 0.3048 0.9906) (xy 0.3048 -0.1016)
			)
			(stroke
				(width 0)
				(type default)
			)
			(fill no)
			(layer "B.CrtYd")
		)
		(fp_line
			(start 0.3048 0.9906)
			(end -0.3048 0.9906)
			(stroke
				(width 0.1)
				(type default)
			)
			(layer "B.Fab")
		)
		(fp_line
			(start 0.3048 -0.1016)
			(end 0.3048 0.9906)
			(stroke
				(width 0.1)
				(type default)
			)
			(layer "B.Fab")
		)
		(fp_line
			(start -0.3048 0.9906)
			(end -0.3048 -0.1016)
			(stroke
				(width 0.1)
				(type default)
			)
			(layer "B.Fab")
		)
		(fp_line
			(start -0.3048 -0.1016)
			(end 0.3048 -0.1016)
			(stroke
				(width 0.1)
				(type default)
			)
			(layer "B.Fab")
		)
		(pad "1" smd rect
			(at 0 0)
			(size 0.508 0.508)
			(layers "B.Cu" "B.Mask" "B.Paste")
			(net "VCC_PA_3V3")
		)
		(pad "2" smd rect
			(at 0 0.889)
			(size 0.508 0.508)
			(layers "B.Cu" "B.Mask" "B.Paste")
			(net "GND")
		)
		(zone
			(layer "B.Cu")
			(hatch none 0.5)
			(connect_pads
				(clearance 0)
			)
			(min_thickness 0.25)
			(keepout
				(tracks not_allowed)
				(vias allowed)
				(pads allowed)
				(copperpour not_allowed)
				(footprints allowed)
			)
			(placement
				(enabled no)
				(sheetname "")
			)
			(fill
				(thermal_gap 0.5)
				(thermal_bridge_width 0.5)
				(island_removal_mode 0)
			)
			(polygon
				(pts
					(xy 423.946574 -41.617646) (xy 424.454574 -41.617646) (xy 424.454574 -41.236646) (xy 423.946574 -41.236646)
				)
			)
		)
		(zone
			(layer "B.Cu")
			(hatch none 0.5)
			(connect_pads
				(clearance 0)
			)
			(min_thickness 0.25)
			(keepout
				(tracks allowed)
				(vias not_allowed)
				(pads allowed)
				(copperpour not_allowed)
				(footprints allowed)
			)
			(placement
				(enabled no)
				(sheetname "")
			)
			(fill
				(thermal_gap 0.5)
				(thermal_bridge_width 0.5)
				(island_removal_mode 0)
			)
			(polygon
				(pts
					(xy 423.946574 -41.236646) (xy 424.454574 -41.236646) (xy 424.454574 -41.617646) (xy 423.946574 -41.617646)
				)
			)
		)
	)
	(footprint ""
		(layer "B.Cu")
		(at 295.153588 -66.330322 90)
		(property "Reference" "R4P21"
			(at 0 0 90)
			(layer "B.SilkS")
			(hide yes)
			(effects
				(font
					(size 1.27 1.27)
				)
				(justify mirror)
			)
		)
		(property "Value" ""
			(at 0 0 90)
			(layer "B.Fab")
			(effects
				(font
					(size 1.27 1.27)
				)
				(justify mirror)
			)
		)
		(duplicate_pad_numbers_are_jumpers no)
		(fp_poly
			(pts
				(xy 0.2794 -0.1016) (xy -0.2794 -0.1016) (xy -0.2794 0.9906) (xy 0.2794 0.9906)
			)
			(stroke
				(width 0)
				(type default)
			)
			(fill no)
			(layer "B.CrtYd")
		)
		(fp_line
			(start 0.2794 -0.1016)
			(end 0.2794 0.9906)
			(stroke
				(width 0.1)
				(type default)
			)
			(layer "B.Fab")
		)
		(fp_line
			(start -0.2794 -0.1016)
			(end 0.2794 -0.1016)
			(stroke
				(width 0.1)
				(type default)
			)
			(layer "B.Fab")
		)
		(fp_line
			(start 0.2794 0.9906)
			(end -0.2794 0.9906)
			(stroke
				(width 0.1)
				(type default)
			)
			(layer "B.Fab")
		)
		(fp_line
			(start -0.2794 0.9906)
			(end -0.2794 -0.1016)
			(stroke
				(width 0.1)
				(type default)
			)
			(layer "B.Fab")
		)
		(pad "1" smd rect
			(at 0 0 270)
			(size 0.508 0.508)
			(layers "B.Cu" "B.Mask" "B.Paste")
			(net "PVCCIO_CPU0")
		)
		(pad "2" smd rect
			(at 0 0.889 270)
			(size 0.508 0.508)
			(layers "B.Cu" "B.Mask" "B.Paste")
			(net "PU_CPU0_TSC_SYNC")
		)
		(zone
			(layer "B.Cu")
			(hatch none 0.5)
			(connect_pads
				(clearance 0)
			)
			(min_thickness 0.25)
			(keepout
				(tracks allowed)
				(vias not_allowed)
				(pads allowed)
				(copperpour not_allowed)
				(footprints allowed)
			)
			(placement
				(enabled no)
				(sheetname "")
			)
			(fill
				(thermal_gap 0.5)
				(thermal_bridge_width 0.5)
				(island_removal_mode 0)
			)
			(polygon
				(pts
					(xy 295.407588 -66.584322) (xy 295.407588 -66.076322) (xy 295.788588 -66.076322) (xy 295.788588 -66.584322)
				)
			)
		)
		(zone
			(layer "B.Cu")
			(hatch none 0.5)
			(connect_pads
				(clearance 0)
			)
			(min_thickness 0.25)
			(keepout
				(tracks not_allowed)
				(vias allowed)
				(pads allowed)
				(copperpour not_allowed)
				(footprints allowed)
			)
			(placement
				(enabled no)
				(sheetname "")
			)
			(fill
				(thermal_gap 0.5)
				(thermal_bridge_width 0.5)
				(island_removal_mode 0)
			)
			(polygon
				(pts
					(xy 295.788588 -66.584322) (xy 295.788588 -66.076322) (xy 295.407588 -66.076322) (xy 295.407588 -66.584322)
				)
			)
		)
	)
	(footprint ""
		(layer "B.Cu")
		(at 93.081348 -135.3312 -90)
		(property "Reference" "C8M8"
			(at 0 0 90)
			(layer "B.SilkS")
			(hide yes)
			(effects
				(font
					(size 1.27 1.27)
				)
				(justify mirror)
			)
		)
		(property "Value" ""
			(at 0 0 90)
			(layer "B.Fab")
			(effects
				(font
					(size 1.27 1.27)
				)
				(justify mirror)
			)
		)
		(duplicate_pad_numbers_are_jumpers no)
		(fp_rect
			(start 0.500126 1.598422)
			(end -0.500126 -0.201422)
			(stroke
				(width 0)
				(type default)
			)
			(fill no)
			(layer "B.CrtYd")
		)
		(fp_line
			(start -0.500126 1.598422)
			(end 0.500126 1.598422)
			(stroke
				(width 0.1)
				(type default)
			)
			(layer "B.Fab")
		)
		(fp_line
			(start 0.500126 1.598422)
			(end 0.500126 -0.201422)
			(stroke
				(width 0.1)
				(type default)
			)
			(layer "B.Fab")
		)
		(fp_line
			(start -0.500126 -0.201422)
			(end -0.500126 1.598422)
			(stroke
				(width 0.1)
				(type default)
			)
			(layer "B.Fab")
		)
		(fp_line
			(start 0.500126 -0.201422)
			(end -0.500126 -0.201422)
			(stroke
				(width 0.1)
				(type default)
			)
			(layer "B.Fab")
		)
		(pad "1" smd rect
			(at 0 0 180)
			(size 0.889 0.9906)
			(layers "B.Cu" "B.Mask" "B.Paste")
			(net "PVDDQ_KLM")
		)
		(pad "2" smd rect
			(at 0 1.397 180)
			(size 0.889 0.9906)
			(layers "B.Cu" "B.Mask" "B.Paste")
			(net "GND")
		)
		(zone
			(layer "B.Cu")
			(hatch none 0.5)
			(connect_pads
				(clearance 0)
			)
			(min_thickness 0.25)
			(keepout
				(tracks not_allowed)
				(vias allowed)
				(pads allowed)
				(copperpour not_allowed)
				(footprints allowed)
			)
			(placement
				(enabled no)
				(sheetname "")
			)
			(fill
				(thermal_gap 0.5)
				(thermal_bridge_width 0.5)
				(island_removal_mode 0)
			)
			(polygon
				(pts
					(xy 92.128848 -134.8359) (xy 92.636848 -134.8359) (xy 92.636848 -135.8265) (xy 92.128848 -135.8265)
				)
			)
		)
		(zone
			(layer "B.Cu")
			(hatch none 0.5)
			(connect_pads
				(clearance 0)
			)
			(min_thickness 0.25)
			(keepout
				(tracks allowed)
				(vias not_allowed)
				(pads allowed)
				(copperpour not_allowed)
				(footprints allowed)
			)
			(placement
				(enabled no)
				(sheetname "")
			)
			(fill
				(thermal_gap 0.5)
				(thermal_bridge_width 0.5)
				(island_removal_mode 0)
			)
			(polygon
				(pts
					(xy 92.128848 -134.8359) (xy 92.636848 -134.8359) (xy 92.636848 -135.8265) (xy 92.128848 -135.8265)
				)
			)
		)
	)
)
